# BARRELEYE_G2-FPDB_POST-PVT-X02-BOM-X05-20171123_Final.xls.xlsx — TBD AVL Qual (bom)
| NOTES: |  |  |  |  |  |  |
| The following items are alternates to the items listed in the Critical Components Qual tab. |  |  |  |  |  |  |
| These components will be included on near future, non-customer builds for validation and approval by both Customer and the ODM. |  |  |  |  |  |  |
| Item Description | ODM P/N | Customer PN | Vendor | Vendor PN | Build ?? | Estimated Completion Date |
| SATA connectors (black) |  |  |  |  |  |  |
| -  Alternate |  |  |  |  |  |  |
| SATA connectors (blue) |  |  |  |  |  |  |
| -  Alternate |  |  |  |  |  |  |
| PCIe retention |  |  |  |  |  |  |
| -  Alternate |  |  |  |  |  |  |
| RTC XTAL |  |  |  |  |  |  |
| -  Alternate |  |  |  |  |  |  |
| XTAL |  |  |  |  |  |  |
| -  Alternate |  |  |  |  |  |  |
